(kicad_pcb
	(version 20260206)
	(generator "pcbnew")
	(generator_version "10.0")
	(general
		(thickness 1.6)
		(legacy_teardrops no)
	)
	(paper "A4")
	(title_block
		(title "panther-plus-userver — 13130-1b_20150205.brd")
		(comment 1 "Honey Badger (Wiwynn) / footprint 624 of 1509 (DIMM4), pads 149-155 of 210")
	)
	(layers
		(0 "F.Cu" signal "TOP")
		(4 "In1.Cu" signal "L2")
		(6 "In2.Cu" signal "L3")
		(8 "In3.Cu" signal "L4")
		(10 "In4.Cu" signal "L5")
		(12 "In5.Cu" signal "L6")
		(14 "In6.Cu" signal "L7")
		(16 "In7.Cu" signal "L8")
		(18 "In8.Cu" signal "L9")
		(20 "In9.Cu" signal "L10")
		(22 "In10.Cu" signal "L11")
		(2 "B.Cu" signal "BOTTOM")
		(9 "F.Adhes" user "F.Adhesive")
		(11 "B.Adhes" user "B.Adhesive")
		(13 "F.Paste" user "Package Geometry/Pastemask Top")
		(15 "B.Paste" user "Package Geometry/Pastemask Bottom")
		(5 "F.SilkS" user "Ref Des/Silkscreen Top")
		(7 "B.SilkS" user "Ref Des/Silkscreen Bottom")
		(1 "F.Mask" user "Board Geometry/Soldermask Top")
		(3 "B.Mask" user "Board Geometry/Soldermask Bottom")
		(17 "Dwgs.User" user "User.Drawings")
		(19 "Cmts.User" user "User.Comments")
		(21 "Eco1.User" user "User.Eco1")
		(23 "Eco2.User" user "User.Eco2")
		(25 "Edge.Cuts" user "Board Geometry/Outline")
		(27 "Margin" user)
		(31 "F.CrtYd" user "Package Geometry/Place Bound Top")
		(29 "B.CrtYd" user "Package Geometry/Place Bound Bottom")
		(35 "F.Fab" user "Ref Des/Assembly Top")
		(33 "B.Fab" user "Ref Des/Assembly Bottom")
	)
	(footprint ""
		(layer "F.Cu")
		(at 159.999934 -5.790692)
		(property "Reference" "DIMM4"
			(at 0 0 0)
			(layer "F.SilkS")
			(hide yes)
			(effects
				(font
					(size 1.27 1.27)
				)
			)
		)
		(property "Value" "DDR3-204P-174-COLAY-1-GP"
			(at -40.682164 -17.468088 0)
			(unlocked yes)
			(layer "F.Fab")
			(hide yes)
			(effects
				(font
					(size 1.016 1.016)
					(thickness 0.1524)
				)
			)
		)
		(property "Device Type" "AS0A626-H8SN-7H-COLAY-1"
			(at -40.682164 -18.992088 0)
			(unlocked yes)
			(layer "F.Fab")
			(hide yes)
			(effects
				(font
					(size 1.016 1.016)
					(thickness 0.1524)
				)
			)
		)
		(duplicate_pad_numbers_are_jumpers no)
		(pad "147" smd custom
			(at 14.549882 4.106672)
			(size 0.1143 0.1143)
			(layers "F.Cu" "F.Mask" "F.Paste")
			(net "M_B_DQ39")
			(options
				(clearance outline)
				(anchor circle)
			)
			(primitives
				(gr_poly
					(pts
						(xy 0 0.9017) (xy -0.03175 0.89916) (xy -0.0635 0.889) (xy -0.09144 0.87376) (xy -0.11684 0.85344)
						(xy -0.13716 0.82804) (xy -0.1524 0.8001) (xy -0.16256 0.76835) (xy -0.1651 0.7366) (xy -0.1651 0.11938)
						(xy -0.17272 0.11176) (xy -0.19812 0.0762) (xy -0.2032 0.06604) (xy -0.20701 0.05715) (xy -0.21209 0.04699)
						(xy -0.2159 0.03683) (xy -0.21844 0.02667) (xy -0.22225 0.01524) (xy -0.22352 0.00508) (xy -0.22606 -0.00508)
						(xy -0.22733 -0.01651) (xy -0.22733 -0.02667) (xy -0.2286 -0.0381) (xy -0.22733 -0.04953) (xy -0.22733 -0.05969)
						(xy -0.22606 -0.07112) (xy -0.22352 -0.08128) (xy -0.22225 -0.09144) (xy -0.21844 -0.10287) (xy -0.2159 -0.11303)
						(xy -0.21209 -0.12319) (xy -0.20701 -0.13335) (xy -0.2032 -0.14224) (xy -0.19812 -0.1524) (xy -0.17272 -0.18796)
						(xy -0.1651 -0.19558) (xy -0.1651 -0.7366) (xy -0.16256 -0.76835) (xy -0.1524 -0.8001) (xy -0.13716 -0.82804)
						(xy -0.11684 -0.85344) (xy -0.09144 -0.87376) (xy -0.0635 -0.889) (xy -0.03175 -0.89916) (xy 0 -0.9017)
						(xy 0.03175 -0.89916) (xy 0.0635 -0.889) (xy 0.09144 -0.87376) (xy 0.11684 -0.85344) (xy 0.13716 -0.82804)
						(xy 0.1524 -0.8001) (xy 0.16256 -0.76835) (xy 0.1651 -0.7366) (xy 0.1651 -0.19685) (xy 0.17272 -0.18923)
						(xy 0.17907 -0.18034) (xy 0.18669 -0.17145) (xy 0.19177 -0.16256) (xy 0.19812 -0.15367) (xy 0.20828 -0.13335)
						(xy 0.21971 -0.10287) (xy 0.22225 -0.09271) (xy 0.22479 -0.08128) (xy 0.22606 -0.07112) (xy 0.2286 -0.05969)
						(xy 0.2286 -0.01651) (xy 0.22606 -0.00508) (xy 0.22479 0.00508) (xy 0.22225 0.01651) (xy 0.21971 0.02667)
						(xy 0.20828 0.05715) (xy 0.19812 0.07747) (xy 0.19177 0.08636) (xy 0.18669 0.09525) (xy 0.17907 0.10414)
						(xy 0.17272 0.11303) (xy 0.1651 0.12065) (xy 0.1651 0.7366) (xy 0.16256 0.76835) (xy 0.1524 0.8001)
						(xy 0.13716 0.82804) (xy 0.11684 0.85344) (xy 0.09144 0.87376) (xy 0.0635 0.889) (xy 0.03175 0.89916)
					)
					(width 0)
					(fill yes)
				)
			)
		)
		(pad "148" smd custom
			(at 14.85011 -4.106672)
			(size 0.1143 0.1143)
			(layers "F.Cu" "F.Mask" "F.Paste")
			(net "M_B_DQ40")
			(options
				(clearance outline)
				(anchor circle)
			)
			(primitives
				(gr_poly
					(pts
						(xy 0 0.9017) (xy -0.03175 0.89916) (xy -0.0635 0.889) (xy -0.09144 0.87376) (xy -0.11684 0.85344)
						(xy -0.13716 0.82804) (xy -0.1524 0.8001) (xy -0.16256 0.76835) (xy -0.1651 0.7366) (xy -0.1651 0.19685)
						(xy -0.17272 0.18923) (xy -0.17907 0.18034) (xy -0.18669 0.17145) (xy -0.19177 0.16256) (xy -0.19812 0.15367)
						(xy -0.20828 0.13335) (xy -0.21971 0.10287) (xy -0.22225 0.09271) (xy -0.22479 0.08128) (xy -0.22606 0.07112)
						(xy -0.2286 0.05969) (xy -0.2286 0.01651) (xy -0.22606 0.00508) (xy -0.22479 -0.00508) (xy -0.22225 -0.01651)
						(xy -0.21971 -0.02667) (xy -0.20828 -0.05715) (xy -0.19812 -0.07747) (xy -0.19177 -0.08636) (xy -0.18669 -0.09525)
						(xy -0.17907 -0.10414) (xy -0.17272 -0.11303) (xy -0.1651 -0.12065) (xy -0.1651 -0.7366) (xy -0.16256 -0.76835)
						(xy -0.1524 -0.8001) (xy -0.13716 -0.82804) (xy -0.11684 -0.85344) (xy -0.09144 -0.87376) (xy -0.0635 -0.889)
						(xy -0.03175 -0.89916) (xy 0 -0.9017) (xy 0.03175 -0.89916) (xy 0.0635 -0.889) (xy 0.09144 -0.87376)
						(xy 0.11684 -0.85344) (xy 0.13716 -0.82804) (xy 0.1524 -0.8001) (xy 0.16256 -0.76835) (xy 0.1651 -0.7366)
						(xy 0.1651 -0.11938) (xy 0.17272 -0.11176) (xy 0.19812 -0.0762) (xy 0.2032 -0.06604) (xy 0.20701 -0.05715)
						(xy 0.21209 -0.04699) (xy 0.2159 -0.03683) (xy 0.21844 -0.02667) (xy 0.22225 -0.01524) (xy 0.22352 -0.00508)
						(xy 0.22606 0.00508) (xy 0.22733 0.01651) (xy 0.22733 0.02667) (xy 0.2286 0.0381) (xy 0.22733 0.04953)
						(xy 0.22733 0.05969) (xy 0.22606 0.07112) (xy 0.22352 0.08128) (xy 0.22225 0.09144) (xy 0.21844 0.10287)
						(xy 0.2159 0.11303) (xy 0.21209 0.12319) (xy 0.20701 0.13335) (xy 0.2032 0.14224) (xy 0.19812 0.1524)
						(xy 0.17272 0.18796) (xy 0.1651 0.19558) (xy 0.1651 0.7366) (xy 0.16256 0.76835) (xy 0.1524 0.8001)
						(xy 0.13716 0.82804) (xy 0.11684 0.85344) (xy 0.09144 0.87376) (xy 0.0635 0.889) (xy 0.03175 0.89916)
					)
					(width 0)
					(fill yes)
				)
			)
		)
		(pad "149" smd custom
			(at 15.150084 4.106672)
			(size 0.1143 0.1143)
			(layers "F.Cu" "F.Mask" "F.Paste")
			(net "GND")
			(options
				(clearance outline)
				(anchor circle)
			)
			(primitives
				(gr_poly
					(pts
						(xy 0 0.9017) (xy -0.03175 0.89916) (xy -0.0635 0.889) (xy -0.09144 0.87376) (xy -0.11684 0.85344)
						(xy -0.13716 0.82804) (xy -0.1524 0.8001) (xy -0.16256 0.76835) (xy -0.1651 0.7366) (xy -0.1651 -0.13462)
						(xy -0.17272 -0.14224) (xy -0.19812 -0.1778) (xy -0.2032 -0.18796) (xy -0.20701 -0.19685) (xy -0.21209 -0.20701)
						(xy -0.2159 -0.21717) (xy -0.21844 -0.22733) (xy -0.22225 -0.23876) (xy -0.22352 -0.24892) (xy -0.22606 -0.25908)
						(xy -0.22733 -0.27051) (xy -0.22733 -0.28067) (xy -0.2286 -0.2921) (xy -0.22733 -0.30353) (xy -0.22733 -0.31369)
						(xy -0.22606 -0.32512) (xy -0.22352 -0.33528) (xy -0.22225 -0.34544) (xy -0.21844 -0.35687) (xy -0.2159 -0.36703)
						(xy -0.21209 -0.37719) (xy -0.20701 -0.38735) (xy -0.2032 -0.39624) (xy -0.19812 -0.4064) (xy -0.17272 -0.44196)
						(xy -0.1651 -0.44958) (xy -0.1651 -0.7366) (xy -0.16256 -0.76835) (xy -0.1524 -0.8001) (xy -0.13716 -0.82804)
						(xy -0.11684 -0.85344) (xy -0.09144 -0.87376) (xy -0.0635 -0.889) (xy -0.03175 -0.89916) (xy 0 -0.9017)
						(xy 0.03175 -0.89916) (xy 0.0635 -0.889) (xy 0.09144 -0.87376) (xy 0.11684 -0.85344) (xy 0.13716 -0.82804)
						(xy 0.1524 -0.8001) (xy 0.16256 -0.76835) (xy 0.1651 -0.7366) (xy 0.1651 -0.44958) (xy 0.17272 -0.44196)
						(xy 0.19812 -0.4064) (xy 0.2032 -0.39624) (xy 0.20701 -0.38735) (xy 0.21209 -0.37719) (xy 0.2159 -0.36703)
						(xy 0.21844 -0.35687) (xy 0.22225 -0.34544) (xy 0.22352 -0.33528) (xy 0.22606 -0.32512) (xy 0.22733 -0.31369)
						(xy 0.22733 -0.30353) (xy 0.2286 -0.2921) (xy 0.22733 -0.28067) (xy 0.22733 -0.27051) (xy 0.22606 -0.25908)
						(xy 0.22352 -0.24892) (xy 0.22225 -0.23876) (xy 0.21844 -0.22733) (xy 0.2159 -0.21717) (xy 0.21209 -0.20701)
						(xy 0.20701 -0.19685) (xy 0.2032 -0.18796) (xy 0.19812 -0.1778) (xy 0.17272 -0.14224) (xy 0.1651 -0.13462)
						(xy 0.1651 0.7366) (xy 0.16256 0.76835) (xy 0.1524 0.8001) (xy 0.13716 0.82804) (xy 0.11684 0.85344)
						(xy 0.09144 0.87376) (xy 0.0635 0.889) (xy 0.03175 0.89916)
					)
					(width 0)
					(fill yes)
				)
			)
		)
		(pad "150" smd custom
			(at 15.450058 -4.106672)
			(size 0.1143 0.1143)
			(layers "F.Cu" "F.Mask" "F.Paste")
			(net "M_B_DQ41")
			(options
				(clearance outline)
				(anchor circle)
			)
			(primitives
				(gr_poly
					(pts
						(xy 0 0.9017) (xy -0.03175 0.89916) (xy -0.0635 0.889) (xy -0.09144 0.87376) (xy -0.11684 0.85344)
						(xy -0.13716 0.82804) (xy -0.1524 0.8001) (xy -0.16256 0.76835) (xy -0.1651 0.7366) (xy -0.1651 0.44958)
						(xy -0.17272 0.44196) (xy -0.19812 0.4064) (xy -0.2032 0.39624) (xy -0.20701 0.38735) (xy -0.21209 0.37719)
						(xy -0.2159 0.36703) (xy -0.21844 0.35687) (xy -0.22225 0.34544) (xy -0.22352 0.33528) (xy -0.22606 0.32512)
						(xy -0.22733 0.31369) (xy -0.22733 0.30353) (xy -0.2286 0.2921) (xy -0.22733 0.28067) (xy -0.22733 0.27051)
						(xy -0.22606 0.25908) (xy -0.22352 0.24892) (xy -0.22225 0.23876) (xy -0.21844 0.22733) (xy -0.2159 0.21717)
						(xy -0.21209 0.20701) (xy -0.20701 0.19685) (xy -0.2032 0.18796) (xy -0.19812 0.1778) (xy -0.17272 0.14224)
						(xy -0.1651 0.13462) (xy -0.1651 -0.7366) (xy -0.16256 -0.76835) (xy -0.1524 -0.8001) (xy -0.13716 -0.82804)
						(xy -0.11684 -0.85344) (xy -0.09144 -0.87376) (xy -0.0635 -0.889) (xy -0.03175 -0.89916) (xy 0 -0.9017)
						(xy 0.03175 -0.89916) (xy 0.0635 -0.889) (xy 0.09144 -0.87376) (xy 0.11684 -0.85344) (xy 0.13716 -0.82804)
						(xy 0.1524 -0.8001) (xy 0.16256 -0.76835) (xy 0.1651 -0.7366) (xy 0.1651 0.13462) (xy 0.17272 0.14224)
						(xy 0.19812 0.1778) (xy 0.2032 0.18796) (xy 0.20701 0.19685) (xy 0.21209 0.20701) (xy 0.2159 0.21717)
						(xy 0.21844 0.22733) (xy 0.22225 0.23876) (xy 0.22352 0.24892) (xy 0.22606 0.25908) (xy 0.22733 0.27051)
						(xy 0.22733 0.28067) (xy 0.2286 0.2921) (xy 0.22733 0.30353) (xy 0.22733 0.31369) (xy 0.22606 0.32512)
						(xy 0.22352 0.33528) (xy 0.22225 0.34544) (xy 0.21844 0.35687) (xy 0.2159 0.36703) (xy 0.21209 0.37719)
						(xy 0.20701 0.38735) (xy 0.2032 0.39624) (xy 0.19812 0.4064) (xy 0.17272 0.44196) (xy 0.1651 0.44958)
						(xy 0.1651 0.7366) (xy 0.16256 0.76835) (xy 0.1524 0.8001) (xy 0.13716 0.82804) (xy 0.11684 0.85344)
						(xy 0.09144 0.87376) (xy 0.0635 0.889) (xy 0.03175 0.89916)
					)
					(width 0)
					(fill yes)
				)
			)
		)
		(pad "151" smd custom
			(at 15.750032 4.106672)
			(size 0.1143 0.1143)
			(layers "F.Cu" "F.Mask" "F.Paste")
			(net "M_B_DQ44")
			(options
				(clearance outline)
				(anchor circle)
			)
			(primitives
				(gr_poly
					(pts
						(xy 0 0.9017) (xy -0.03175 0.89916) (xy -0.0635 0.889) (xy -0.09144 0.87376) (xy -0.11684 0.85344)
						(xy -0.13716 0.82804) (xy -0.1524 0.8001) (xy -0.16256 0.76835) (xy -0.1651 0.7366) (xy -0.1651 0.11938)
						(xy -0.17272 0.11176) (xy -0.19812 0.0762) (xy -0.2032 0.06604) (xy -0.20701 0.05715) (xy -0.21209 0.04699)
						(xy -0.2159 0.03683) (xy -0.21844 0.02667) (xy -0.22225 0.01524) (xy -0.22352 0.00508) (xy -0.22606 -0.00508)
						(xy -0.22733 -0.01651) (xy -0.22733 -0.02667) (xy -0.2286 -0.0381) (xy -0.22733 -0.04953) (xy -0.22733 -0.05969)
						(xy -0.22606 -0.07112) (xy -0.22352 -0.08128) (xy -0.22225 -0.09144) (xy -0.21844 -0.10287) (xy -0.2159 -0.11303)
						(xy -0.21209 -0.12319) (xy -0.20701 -0.13335) (xy -0.2032 -0.14224) (xy -0.19812 -0.1524) (xy -0.17272 -0.18796)
						(xy -0.1651 -0.19558) (xy -0.1651 -0.7366) (xy -0.16256 -0.76835) (xy -0.1524 -0.8001) (xy -0.13716 -0.82804)
						(xy -0.11684 -0.85344) (xy -0.09144 -0.87376) (xy -0.0635 -0.889) (xy -0.03175 -0.89916) (xy 0 -0.9017)
						(xy 0.03175 -0.89916) (xy 0.0635 -0.889) (xy 0.09144 -0.87376) (xy 0.11684 -0.85344) (xy 0.13716 -0.82804)
						(xy 0.1524 -0.8001) (xy 0.16256 -0.76835) (xy 0.1651 -0.7366) (xy 0.1651 -0.19685) (xy 0.17272 -0.18923)
						(xy 0.17907 -0.18034) (xy 0.18669 -0.17145) (xy 0.19177 -0.16256) (xy 0.19812 -0.15367) (xy 0.20828 -0.13335)
						(xy 0.21971 -0.10287) (xy 0.22225 -0.09271) (xy 0.22479 -0.08128) (xy 0.22606 -0.07112) (xy 0.2286 -0.05969)
						(xy 0.2286 -0.01651) (xy 0.22606 -0.00508) (xy 0.22479 0.00508) (xy 0.22225 0.01651) (xy 0.21971 0.02667)
						(xy 0.20828 0.05715) (xy 0.19812 0.07747) (xy 0.19177 0.08636) (xy 0.18669 0.09525) (xy 0.17907 0.10414)
						(xy 0.17272 0.11303) (xy 0.1651 0.12065) (xy 0.1651 0.7366) (xy 0.16256 0.76835) (xy 0.1524 0.8001)
						(xy 0.13716 0.82804) (xy 0.11684 0.85344) (xy 0.09144 0.87376) (xy 0.0635 0.889) (xy 0.03175 0.89916)
					)
					(width 0)
					(fill yes)
				)
			)
		)
		(pad "152" smd custom
			(at 16.050006 -4.106672)
			(size 0.1143 0.1143)
			(layers "F.Cu" "F.Mask" "F.Paste")
			(net "GND")
			(options
				(clearance outline)
				(anchor circle)
			)
			(primitives
				(gr_poly
					(pts
						(xy 0 0.9017) (xy -0.03175 0.89916) (xy -0.0635 0.889) (xy -0.09144 0.87376) (xy -0.11684 0.85344)
						(xy -0.13716 0.82804) (xy -0.1524 0.8001) (xy -0.16256 0.76835) (xy -0.1651 0.7366) (xy -0.1651 0.19685)
						(xy -0.17272 0.18923) (xy -0.17907 0.18034) (xy -0.18669 0.17145) (xy -0.19177 0.16256) (xy -0.19812 0.15367)
						(xy -0.20828 0.13335) (xy -0.21971 0.10287) (xy -0.22225 0.09271) (xy -0.22479 0.08128) (xy -0.22606 0.07112)
						(xy -0.2286 0.05969) (xy -0.2286 0.01651) (xy -0.22606 0.00508) (xy -0.22479 -0.00508) (xy -0.22225 -0.01651)
						(xy -0.21971 -0.02667) (xy -0.20828 -0.05715) (xy -0.19812 -0.07747) (xy -0.19177 -0.08636) (xy -0.18669 -0.09525)
						(xy -0.17907 -0.10414) (xy -0.17272 -0.11303) (xy -0.1651 -0.12065) (xy -0.1651 -0.7366) (xy -0.16256 -0.76835)
						(xy -0.1524 -0.8001) (xy -0.13716 -0.82804) (xy -0.11684 -0.85344) (xy -0.09144 -0.87376) (xy -0.0635 -0.889)
						(xy -0.03175 -0.89916) (xy 0 -0.9017) (xy 0.03175 -0.89916) (xy 0.0635 -0.889) (xy 0.09144 -0.87376)
						(xy 0.11684 -0.85344) (xy 0.13716 -0.82804) (xy 0.1524 -0.8001) (xy 0.16256 -0.76835) (xy 0.1651 -0.7366)
						(xy 0.1651 -0.11938) (xy 0.17272 -0.11176) (xy 0.19812 -0.0762) (xy 0.2032 -0.06604) (xy 0.20701 -0.05715)
						(xy 0.21209 -0.04699) (xy 0.2159 -0.03683) (xy 0.21844 -0.02667) (xy 0.22225 -0.01524) (xy 0.22352 -0.00508)
						(xy 0.22606 0.00508) (xy 0.22733 0.01651) (xy 0.22733 0.02667) (xy 0.2286 0.0381) (xy 0.22733 0.04953)
						(xy 0.22733 0.05969) (xy 0.22606 0.07112) (xy 0.22352 0.08128) (xy 0.22225 0.09144) (xy 0.21844 0.10287)
						(xy 0.2159 0.11303) (xy 0.21209 0.12319) (xy 0.20701 0.13335) (xy 0.2032 0.14224) (xy 0.19812 0.1524)
						(xy 0.17272 0.18796) (xy 0.1651 0.19558) (xy 0.1651 0.7366) (xy 0.16256 0.76835) (xy 0.1524 0.8001)
						(xy 0.13716 0.82804) (xy 0.11684 0.85344) (xy 0.09144 0.87376) (xy 0.0635 0.889) (xy 0.03175 0.89916)
					)
					(width 0)
					(fill yes)
				)
			)
		)
		(pad "153" smd custom
			(at 16.34998 4.106672)
			(size 0.1143 0.1143)
			(layers "F.Cu" "F.Mask" "F.Paste")
			(net "M_B_DQ45")
			(options
				(clearance outline)
				(anchor circle)
			)
			(primitives
				(gr_poly
					(pts
						(xy 0 0.9017) (xy -0.03175 0.89916) (xy -0.0635 0.889) (xy -0.09144 0.87376) (xy -0.11684 0.85344)
						(xy -0.13716 0.82804) (xy -0.1524 0.8001) (xy -0.16256 0.76835) (xy -0.1651 0.7366) (xy -0.1651 -0.13462)
						(xy -0.17272 -0.14224) (xy -0.19812 -0.1778) (xy -0.2032 -0.18796) (xy -0.20701 -0.19685) (xy -0.21209 -0.20701)
						(xy -0.2159 -0.21717) (xy -0.21844 -0.22733) (xy -0.22225 -0.23876) (xy -0.22352 -0.24892) (xy -0.22606 -0.25908)
						(xy -0.22733 -0.27051) (xy -0.22733 -0.28067) (xy -0.2286 -0.2921) (xy -0.22733 -0.30353) (xy -0.22733 -0.31369)
						(xy -0.22606 -0.32512) (xy -0.22352 -0.33528) (xy -0.22225 -0.34544) (xy -0.21844 -0.35687) (xy -0.2159 -0.36703)
						(xy -0.21209 -0.37719) (xy -0.20701 -0.38735) (xy -0.2032 -0.39624) (xy -0.19812 -0.4064) (xy -0.17272 -0.44196)
						(xy -0.1651 -0.44958) (xy -0.1651 -0.7366) (xy -0.16256 -0.76835) (xy -0.1524 -0.8001) (xy -0.13716 -0.82804)
						(xy -0.11684 -0.85344) (xy -0.09144 -0.87376) (xy -0.0635 -0.889) (xy -0.03175 -0.89916) (xy 0 -0.9017)
						(xy 0.03175 -0.89916) (xy 0.0635 -0.889) (xy 0.09144 -0.87376) (xy 0.11684 -0.85344) (xy 0.13716 -0.82804)
						(xy 0.1524 -0.8001) (xy 0.16256 -0.76835) (xy 0.1651 -0.7366) (xy 0.1651 -0.44958) (xy 0.17272 -0.44196)
						(xy 0.19812 -0.4064) (xy 0.2032 -0.39624) (xy 0.20701 -0.38735) (xy 0.21209 -0.37719) (xy 0.2159 -0.36703)
						(xy 0.21844 -0.35687) (xy 0.22225 -0.34544) (xy 0.22352 -0.33528) (xy 0.22606 -0.32512) (xy 0.22733 -0.31369)
						(xy 0.22733 -0.30353) (xy 0.2286 -0.2921) (xy 0.22733 -0.28067) (xy 0.22733 -0.27051) (xy 0.22606 -0.25908)
						(xy 0.22352 -0.24892) (xy 0.22225 -0.23876) (xy 0.21844 -0.22733) (xy 0.2159 -0.21717) (xy 0.21209 -0.20701)
						(xy 0.20701 -0.19685) (xy 0.2032 -0.18796) (xy 0.19812 -0.1778) (xy 0.17272 -0.14224) (xy 0.1651 -0.13462)
						(xy 0.1651 0.7366) (xy 0.16256 0.76835) (xy 0.1524 0.8001) (xy 0.13716 0.82804) (xy 0.11684 0.85344)
						(xy 0.09144 0.87376) (xy 0.0635 0.889) (xy 0.03175 0.89916)
					)
					(width 0)
					(fill yes)
				)
			)
		)
	)
)
